(kicad_pcb
	(version 20260206)
	(generator "pcbnew")
	(generator_version "10.0")
	(general
		(thickness 1.6)
		(legacy_teardrops no)
	)
	(paper "A4")
	(title_block
		(title "v1-chassis-manager — T6M_CM_d_v01_1031_1645.brd")
		(comment 1 "Open CloudServer (Microsoft) / footprints 2294-2303 of 2512")
	)
	(layers
		(0 "F.Cu" signal "TOP")
		(4 "In1.Cu" signal "GND1")
		(6 "In2.Cu" signal "IN1")
		(8 "In3.Cu" signal "VCC1")
		(10 "In4.Cu" signal "VCC2")
		(12 "In5.Cu" signal "GND2")
		(14 "In6.Cu" signal "IN2")
		(16 "In7.Cu" signal "IN3")
		(18 "In8.Cu" signal "GND3")
		(2 "B.Cu" signal "BOTTOM")
		(9 "F.Adhes" user "F.Adhesive")
		(11 "B.Adhes" user "B.Adhesive")
		(13 "F.Paste" user "Package Geometry/Pastemask Top")
		(15 "B.Paste" user "Package Geometry/Pastemask Bottom")
		(5 "F.SilkS" user "Ref Des/Silkscreen Top")
		(7 "B.SilkS" user "Ref Des/Silkscreen Bottom")
		(1 "F.Mask" user "Board Geometry/Soldermask Top")
		(3 "B.Mask" user "Board Geometry/Soldermask Bottom")
		(17 "Dwgs.User" user "User.Drawings")
		(19 "Cmts.User" user "User.Comments")
		(21 "Eco1.User" user "User.Eco1")
		(23 "Eco2.User" user "User.Eco2")
		(25 "Edge.Cuts" user "Board Geometry/Outline")
		(27 "Margin" user)
		(31 "F.CrtYd" user "Package Geometry/Place Bound Top")
		(29 "B.CrtYd" user "Package Geometry/Place Bound Bottom")
		(35 "F.Fab" user "Ref Des/Assembly Top")
		(33 "B.Fab" user "Ref Des/Assembly Bottom")
	)
	(footprint ""
		(layer "B.Cu")
		(at 146.79676 -187.999624 90)
		(property "Reference" "R963"
			(at 4.438396 -1.74625 270)
			(unlocked yes)
			(layer "B.SilkS")
			(effects
				(font
					(size 0.7874 0.5842)
					(thickness 0.1524)
				)
				(justify left mirror)
			)
		)
		(property "Value" ""
			(at 0 0 90)
			(layer "B.Fab")
			(effects
				(font
					(size 1.27 1.27)
				)
				(justify mirror)
			)
		)
		(duplicate_pad_numbers_are_jumpers no)
		(fp_line
			(start 0.7874 -0.4064)
			(end -0.7874 -0.4064)
			(stroke
				(width 0.1524)
				(type default)
			)
			(layer "B.SilkS")
		)
		(fp_line
			(start -0.7874 -0.4064)
			(end -0.7874 0.4064)
			(stroke
				(width 0.1524)
				(type default)
			)
			(layer "B.SilkS")
		)
		(fp_line
			(start 0.7874 0.4064)
			(end 0.7874 -0.4064)
			(stroke
				(width 0.1524)
				(type default)
			)
			(layer "B.SilkS")
		)
		(fp_line
			(start -0.7874 0.4064)
			(end 0.7874 0.4064)
			(stroke
				(width 0.1524)
				(type default)
			)
			(layer "B.SilkS")
		)
		(fp_poly
			(pts
				(xy 0.508 0.2794) (xy 0.508 0.2286) (xy 0.635 0.2286) (xy 0.635 -0.254) (xy 0.5334 -0.254) (xy 0.5334 -0.2794)
				(xy -0.5334 -0.2794) (xy -0.5334 -0.254) (xy -0.635 -0.254) (xy -0.635 0.254) (xy -0.5334 0.254)
				(xy -0.5334 0.2794)
			)
			(stroke
				(width 0)
				(type default)
			)
			(fill no)
			(layer "B.CrtYd")
		)
		(pad "1" smd rect
			(at -0.40005 0 270)
			(size 0.4572 0.508)
			(layers "B.Cu" "B.Mask" "B.Paste")
			(net "UART_T11_NODE2_RXD")
		)
		(pad "2" smd rect
			(at 0.40005 0 270)
			(size 0.4572 0.508)
			(layers "B.Cu" "B.Mask" "B.Paste")
			(net "UART_T11_NODE2_RXD_R")
		)
	)
	(footprint ""
		(layer "B.Cu")
		(at 107.42676 -188.126624 -90)
		(property "Reference" "R838"
			(at -4.080256 -0.664972 270)
			(unlocked yes)
			(layer "B.SilkS")
			(effects
				(font
					(size 0.7874 0.5842)
					(thickness 0.1524)
				)
				(justify left mirror)
			)
		)
		(property "Value" ""
			(at 0 0 90)
			(layer "B.Fab")
			(effects
				(font
					(size 1.27 1.27)
				)
				(justify mirror)
			)
		)
		(duplicate_pad_numbers_are_jumpers no)
		(fp_line
			(start -0.7874 0.4064)
			(end 0.7874 0.4064)
			(stroke
				(width 0.1524)
				(type default)
			)
			(layer "B.SilkS")
		)
		(fp_line
			(start 0.7874 0.4064)
			(end 0.7874 -0.4064)
			(stroke
				(width 0.1524)
				(type default)
			)
			(layer "B.SilkS")
		)
		(fp_line
			(start -0.7874 -0.4064)
			(end -0.7874 0.4064)
			(stroke
				(width 0.1524)
				(type default)
			)
			(layer "B.SilkS")
		)
		(fp_line
			(start 0.7874 -0.4064)
			(end -0.7874 -0.4064)
			(stroke
				(width 0.1524)
				(type default)
			)
			(layer "B.SilkS")
		)
		(fp_poly
			(pts
				(xy 0.508 0.2794) (xy 0.508 0.2286) (xy 0.635 0.2286) (xy 0.635 -0.254) (xy 0.5334 -0.254) (xy 0.5334 -0.2794)
				(xy -0.5334 -0.2794) (xy -0.5334 -0.254) (xy -0.635 -0.254) (xy -0.635 0.254) (xy -0.5334 0.254)
				(xy -0.5334 0.2794)
			)
			(stroke
				(width 0)
				(type default)
			)
			(fill no)
			(layer "B.CrtYd")
		)
		(pad "1" smd rect
			(at -0.40005 0 90)
			(size 0.4572 0.508)
			(layers "B.Cu" "B.Mask" "B.Paste")
			(net "PSU_ALERT_R_N")
		)
		(pad "2" smd rect
			(at 0.40005 0 90)
			(size 0.4572 0.508)
			(layers "B.Cu" "B.Mask" "B.Paste")
			(net "PSU_ALERT_N")
		)
	)
	(footprint ""
		(layer "B.Cu")
		(at 37.621718 -137.4013 180)
		(property "Reference" "C227"
			(at 2.089912 -0.004064 0)
			(unlocked yes)
			(layer "B.SilkS")
			(effects
				(font
					(size 0.7874 0.5842)
					(thickness 0.1524)
				)
				(justify left mirror)
			)
		)
		(property "Value" ""
			(at 0 0 0)
			(layer "B.Fab")
			(effects
				(font
					(size 1.27 1.27)
				)
				(justify mirror)
			)
		)
		(duplicate_pad_numbers_are_jumpers no)
		(fp_line
			(start 0.7874 0.4064)
			(end 0.7874 -0.4064)
			(stroke
				(width 0.1524)
				(type default)
			)
			(layer "B.SilkS")
		)
		(fp_line
			(start 0.7874 -0.4064)
			(end -0.7874 -0.4064)
			(stroke
				(width 0.1524)
				(type default)
			)
			(layer "B.SilkS")
		)
		(fp_line
			(start 0 0.381)
			(end 0 -0.381)
			(stroke
				(width 0.1524)
				(type default)
			)
			(layer "B.SilkS")
		)
		(fp_line
			(start -0.7874 0.4064)
			(end 0.7874 0.4064)
			(stroke
				(width 0.1524)
				(type default)
			)
			(layer "B.SilkS")
		)
		(fp_line
			(start -0.7874 -0.4064)
			(end -0.7874 0.4064)
			(stroke
				(width 0.1524)
				(type default)
			)
			(layer "B.SilkS")
		)
		(fp_poly
			(pts
				(xy 0.5334 0.254) (xy 0.635 0.254) (xy 0.635 0.2286) (xy 0.635 -0.254) (xy 0.5334 -0.254) (xy 0.5334 -0.2794)
				(xy -0.5334 -0.2794) (xy -0.5334 -0.254) (xy -0.635 -0.254) (xy -0.635 0.254) (xy -0.5334 0.254)
				(xy -0.5334 0.2794) (xy 0.508 0.2794) (xy 0.5334 0.2794)
			)
			(stroke
				(width 0)
				(type default)
			)
			(fill no)
			(layer "B.CrtYd")
		)
		(pad "1" smd rect
			(at -0.40005 0)
			(size 0.4572 0.508)
			(layers "B.Cu" "B.Mask" "B.Paste")
			(net "GND")
		)
		(pad "2" smd rect
			(at 0.40005 0)
			(size 0.4572 0.508)
			(layers "B.Cu" "B.Mask" "B.Paste")
			(net "P0V75_BMC_VTTREF_NODE1")
		)
	)
	(footprint ""
		(layer "B.Cu")
		(at 130.794252 -135.87095 -90)
		(property "Reference" "C876"
			(at 5.07365 -0.27813 270)
			(unlocked yes)
			(layer "B.SilkS")
			(effects
				(font
					(size 0.7874 0.5842)
					(thickness 0.1524)
				)
				(justify left mirror)
			)
		)
		(property "Value" ""
			(at 0 0 90)
			(layer "B.Fab")
			(effects
				(font
					(size 1.27 1.27)
				)
				(justify mirror)
			)
		)
		(duplicate_pad_numbers_are_jumpers no)
		(fp_line
			(start -0.7874 0.4064)
			(end 0.7874 0.4064)
			(stroke
				(width 0.1524)
				(type default)
			)
			(layer "B.SilkS")
		)
		(fp_line
			(start 0.7874 0.4064)
			(end 0.7874 -0.4064)
			(stroke
				(width 0.1524)
				(type default)
			)
			(layer "B.SilkS")
		)
		(fp_line
			(start 0 0.381)
			(end 0 -0.381)
			(stroke
				(width 0.1524)
				(type default)
			)
			(layer "B.SilkS")
		)
		(fp_line
			(start -0.7874 -0.4064)
			(end -0.7874 0.4064)
			(stroke
				(width 0.1524)
				(type default)
			)
			(layer "B.SilkS")
		)
		(fp_line
			(start 0.7874 -0.4064)
			(end -0.7874 -0.4064)
			(stroke
				(width 0.1524)
				(type default)
			)
			(layer "B.SilkS")
		)
		(fp_poly
			(pts
				(xy 0.5334 0.254) (xy 0.635 0.254) (xy 0.635 0.2286) (xy 0.635 -0.254) (xy 0.5334 -0.254) (xy 0.5334 -0.2794)
				(xy -0.5334 -0.2794) (xy -0.5334 -0.254) (xy -0.635 -0.254) (xy -0.635 0.254) (xy -0.5334 0.254)
				(xy -0.5334 0.2794) (xy 0.508 0.2794) (xy 0.5334 0.2794)
			)
			(stroke
				(width 0)
				(type default)
			)
			(fill no)
			(layer "B.CrtYd")
		)
		(pad "1" smd rect
			(at -0.40005 0 90)
			(size 0.4572 0.508)
			(layers "B.Cu" "B.Mask" "B.Paste")
			(net "P1V0_NODE1")
		)
		(pad "2" smd rect
			(at 0.40005 0 90)
			(size 0.4572 0.508)
			(layers "B.Cu" "B.Mask" "B.Paste")
			(net "GND")
		)
	)
	(footprint ""
		(layer "B.Cu")
		(at 51.990498 -96.696784 90)
		(property "Reference" "R50"
			(at 6.405118 -4.494276 270)
			(unlocked yes)
			(layer "B.SilkS")
			(effects
				(font
					(size 0.7874 0.5842)
					(thickness 0.1524)
				)
				(justify left mirror)
			)
		)
		(property "Value" ""
			(at 0 0 90)
			(layer "B.Fab")
			(effects
				(font
					(size 1.27 1.27)
				)
				(justify mirror)
			)
		)
		(duplicate_pad_numbers_are_jumpers no)
		(fp_line
			(start 0.7874 -0.4064)
			(end -0.7874 -0.4064)
			(stroke
				(width 0.1524)
				(type default)
			)
			(layer "B.SilkS")
		)
		(fp_line
			(start -0.7874 -0.4064)
			(end -0.7874 0.4064)
			(stroke
				(width 0.1524)
				(type default)
			)
			(layer "B.SilkS")
		)
		(fp_line
			(start 0.7874 0.4064)
			(end 0.7874 -0.4064)
			(stroke
				(width 0.1524)
				(type default)
			)
			(layer "B.SilkS")
		)
		(fp_line
			(start -0.7874 0.4064)
			(end 0.7874 0.4064)
			(stroke
				(width 0.1524)
				(type default)
			)
			(layer "B.SilkS")
		)
		(fp_poly
			(pts
				(xy 0.508 0.2794) (xy 0.508 0.2286) (xy 0.635 0.2286) (xy 0.635 -0.254) (xy 0.5334 -0.254) (xy 0.5334 -0.2794)
				(xy -0.5334 -0.2794) (xy -0.5334 -0.254) (xy -0.635 -0.254) (xy -0.635 0.254) (xy -0.5334 0.254)
				(xy -0.5334 0.2794)
			)
			(stroke
				(width 0)
				(type default)
			)
			(fill no)
			(layer "B.CrtYd")
		)
		(pad "1" smd rect
			(at -0.40005 0 270)
			(size 0.4572 0.508)
			(layers "B.Cu" "B.Mask" "B.Paste")
			(net "PD_CPU_NODE1_DFX_GPIO_GRP1_7")
		)
		(pad "2" smd rect
			(at 0.40005 0 270)
			(size 0.4572 0.508)
			(layers "B.Cu" "B.Mask" "B.Paste")
			(net "GND")
		)
	)
	(footprint ""
		(layer "B.Cu")
		(at 78.83144 -164.377624)
		(property "Reference" "R783"
			(at 30.555946 20.921726 0)
			(unlocked yes)
			(layer "B.SilkS")
			(effects
				(font
					(size 0.7874 0.5842)
					(thickness 0.1524)
				)
				(justify left mirror)
			)
		)
		(property "Value" ""
			(at 0 0 0)
			(layer "B.Fab")
			(effects
				(font
					(size 1.27 1.27)
				)
				(justify mirror)
			)
		)
		(duplicate_pad_numbers_are_jumpers no)
		(fp_line
			(start -0.7874 -0.4064)
			(end -0.7874 0.4064)
			(stroke
				(width 0.1524)
				(type default)
			)
			(layer "B.SilkS")
		)
		(fp_line
			(start -0.7874 0.4064)
			(end 0.7874 0.4064)
			(stroke
				(width 0.1524)
				(type default)
			)
			(layer "B.SilkS")
		)
		(fp_line
			(start 0.7874 -0.4064)
			(end -0.7874 -0.4064)
			(stroke
				(width 0.1524)
				(type default)
			)
			(layer "B.SilkS")
		)
		(fp_line
			(start 0.7874 0.4064)
			(end 0.7874 -0.4064)
			(stroke
				(width 0.1524)
				(type default)
			)
			(layer "B.SilkS")
		)
		(fp_poly
			(pts
				(xy 0.508 0.2794) (xy 0.508 0.2286) (xy 0.635 0.2286) (xy 0.635 -0.254) (xy 0.5334 -0.254) (xy 0.5334 -0.2794)
				(xy -0.5334 -0.2794) (xy -0.5334 -0.254) (xy -0.635 -0.254) (xy -0.635 0.254) (xy -0.5334 0.254)
				(xy -0.5334 0.2794)
			)
			(stroke
				(width 0)
				(type default)
			)
			(fill no)
			(layer "B.CrtYd")
		)
		(pad "1" smd rect
			(at -0.40005 0 180)
			(size 0.4572 0.508)
			(layers "B.Cu" "B.Mask" "B.Paste")
			(net "GND")
		)
		(pad "2" smd rect
			(at 0.40005 0 180)
			(size 0.4572 0.508)
			(layers "B.Cu" "B.Mask" "B.Paste")
			(net "SDC_WAKEUP")
		)
	)
	(footprint ""
		(layer "B.Cu")
		(at 55.10276 -185.205624 90)
		(property "Reference" "C670"
			(at 4.15163 0.207264 270)
			(unlocked yes)
			(layer "B.SilkS")
			(effects
				(font
					(size 0.7874 0.5842)
					(thickness 0.1524)
				)
				(justify left mirror)
			)
		)
		(property "Value" ""
			(at 0 0 90)
			(layer "B.Fab")
			(effects
				(font
					(size 1.27 1.27)
				)
				(justify mirror)
			)
		)
		(duplicate_pad_numbers_are_jumpers no)
		(fp_line
			(start 0.7874 -0.4064)
			(end -0.7874 -0.4064)
			(stroke
				(width 0.1524)
				(type default)
			)
			(layer "B.SilkS")
		)
		(fp_line
			(start -0.7874 -0.4064)
			(end -0.7874 0.4064)
			(stroke
				(width 0.1524)
				(type default)
			)
			(layer "B.SilkS")
		)
		(fp_line
			(start 0 0.381)
			(end 0 -0.381)
			(stroke
				(width 0.1524)
				(type default)
			)
			(layer "B.SilkS")
		)
		(fp_line
			(start 0.7874 0.4064)
			(end 0.7874 -0.4064)
			(stroke
				(width 0.1524)
				(type default)
			)
			(layer "B.SilkS")
		)
		(fp_line
			(start -0.7874 0.4064)
			(end 0.7874 0.4064)
			(stroke
				(width 0.1524)
				(type default)
			)
			(layer "B.SilkS")
		)
		(fp_poly
			(pts
				(xy 0.5334 0.254) (xy 0.635 0.254) (xy 0.635 0.2286) (xy 0.635 -0.254) (xy 0.5334 -0.254) (xy 0.5334 -0.2794)
				(xy -0.5334 -0.2794) (xy -0.5334 -0.254) (xy -0.635 -0.254) (xy -0.635 0.254) (xy -0.5334 0.254)
				(xy -0.5334 0.2794) (xy 0.508 0.2794) (xy 0.5334 0.2794)
			)
			(stroke
				(width 0)
				(type default)
			)
			(fill no)
			(layer "B.CrtYd")
		)
		(pad "1" smd rect
			(at -0.40005 0 270)
			(size 0.4572 0.508)
			(layers "B.Cu" "B.Mask" "B.Paste")
			(net "UART_T1_NODE1_RXD")
		)
		(pad "2" smd rect
			(at 0.40005 0 270)
			(size 0.4572 0.508)
			(layers "B.Cu" "B.Mask" "B.Paste")
			(net "GND")
		)
	)
	(footprint ""
		(layer "B.Cu")
		(at 131.93776 -184.951624 90)
		(property "Reference" "R965"
			(at 4.329176 -2.62763 270)
			(unlocked yes)
			(layer "B.SilkS")
			(effects
				(font
					(size 0.7874 0.5842)
					(thickness 0.1524)
				)
				(justify left mirror)
			)
		)
		(property "Value" ""
			(at 0 0 90)
			(layer "B.Fab")
			(effects
				(font
					(size 1.27 1.27)
				)
				(justify mirror)
			)
		)
		(duplicate_pad_numbers_are_jumpers no)
		(fp_line
			(start 0.7874 -0.4064)
			(end -0.7874 -0.4064)
			(stroke
				(width 0.1524)
				(type default)
			)
			(layer "B.SilkS")
		)
		(fp_line
			(start -0.7874 -0.4064)
			(end -0.7874 0.4064)
			(stroke
				(width 0.1524)
				(type default)
			)
			(layer "B.SilkS")
		)
		(fp_line
			(start 0.7874 0.4064)
			(end 0.7874 -0.4064)
			(stroke
				(width 0.1524)
				(type default)
			)
			(layer "B.SilkS")
		)
		(fp_line
			(start -0.7874 0.4064)
			(end 0.7874 0.4064)
			(stroke
				(width 0.1524)
				(type default)
			)
			(layer "B.SilkS")
		)
		(fp_poly
			(pts
				(xy 0.508 0.2794) (xy 0.508 0.2286) (xy 0.635 0.2286) (xy 0.635 -0.254) (xy 0.5334 -0.254) (xy 0.5334 -0.2794)
				(xy -0.5334 -0.2794) (xy -0.5334 -0.254) (xy -0.635 -0.254) (xy -0.635 0.254) (xy -0.5334 0.254)
				(xy -0.5334 0.2794)
			)
			(stroke
				(width 0)
				(type default)
			)
			(fill no)
			(layer "B.CrtYd")
		)
		(pad "1" smd rect
			(at -0.40005 0 270)
			(size 0.4572 0.508)
			(layers "B.Cu" "B.Mask" "B.Paste")
			(net "UART_T9_NODE2_TXD")
		)
		(pad "2" smd rect
			(at 0.40005 0 270)
			(size 0.4572 0.508)
			(layers "B.Cu" "B.Mask" "B.Paste")
			(net "UART_T9_NODE2_TXD_R")
		)
	)
	(footprint ""
		(layer "B.Cu")
		(at 78.83144 -173.521624 180)
		(property "Reference" "R692"
			(at -30.562296 -20.108164 0)
			(unlocked yes)
			(layer "B.SilkS")
			(effects
				(font
					(size 0.7874 0.5842)
					(thickness 0.1524)
				)
				(justify left mirror)
			)
		)
		(property "Value" ""
			(at 0 0 0)
			(layer "B.Fab")
			(effects
				(font
					(size 1.27 1.27)
				)
				(justify mirror)
			)
		)
		(duplicate_pad_numbers_are_jumpers no)
		(fp_line
			(start 0.7874 0.4064)
			(end 0.7874 -0.4064)
			(stroke
				(width 0.1524)
				(type default)
			)
			(layer "B.SilkS")
		)
		(fp_line
			(start 0.7874 -0.4064)
			(end -0.7874 -0.4064)
			(stroke
				(width 0.1524)
				(type default)
			)
			(layer "B.SilkS")
		)
		(fp_line
			(start -0.7874 0.4064)
			(end 0.7874 0.4064)
			(stroke
				(width 0.1524)
				(type default)
			)
			(layer "B.SilkS")
		)
		(fp_line
			(start -0.7874 -0.4064)
			(end -0.7874 0.4064)
			(stroke
				(width 0.1524)
				(type default)
			)
			(layer "B.SilkS")
		)
		(fp_poly
			(pts
				(xy 0.508 0.2794) (xy 0.508 0.2286) (xy 0.635 0.2286) (xy 0.635 -0.254) (xy 0.5334 -0.254) (xy 0.5334 -0.2794)
				(xy -0.5334 -0.2794) (xy -0.5334 -0.254) (xy -0.635 -0.254) (xy -0.635 0.254) (xy -0.5334 0.254)
				(xy -0.5334 0.2794)
			)
			(stroke
				(width 0)
				(type default)
			)
			(fill no)
			(layer "B.CrtYd")
		)
		(pad "1" smd rect
			(at -0.40005 0)
			(size 0.4572 0.508)
			(layers "B.Cu" "B.Mask" "B.Paste")
			(net "T1_NODE4_EN")
		)
		(pad "2" smd rect
			(at 0.40005 0)
			(size 0.4572 0.508)
			(layers "B.Cu" "B.Mask" "B.Paste")
			(net "P5V_NODE1")
		)
	)
	(footprint ""
		(layer "B.Cu")
		(at 123.70816 -173.394624 180)
		(property "Reference" "R706"
			(at 28.598876 -31.524448 0)
			(unlocked yes)
			(layer "B.SilkS")
			(effects
				(font
					(size 0.7874 0.5842)
					(thickness 0.1524)
				)
				(justify left mirror)
			)
		)
		(property "Value" ""
			(at 0 0 0)
			(layer "B.Fab")
			(effects
				(font
					(size 1.27 1.27)
				)
				(justify mirror)
			)
		)
		(duplicate_pad_numbers_are_jumpers no)
		(fp_line
			(start 0.7874 0.4064)
			(end 0.7874 -0.4064)
			(stroke
				(width 0.1524)
				(type default)
			)
			(layer "B.SilkS")
		)
		(fp_line
			(start 0.7874 -0.4064)
			(end -0.7874 -0.4064)
			(stroke
				(width 0.1524)
				(type default)
			)
			(layer "B.SilkS")
		)
		(fp_line
			(start -0.7874 0.4064)
			(end 0.7874 0.4064)
			(stroke
				(width 0.1524)
				(type default)
			)
			(layer "B.SilkS")
		)
		(fp_line
			(start -0.7874 -0.4064)
			(end -0.7874 0.4064)
			(stroke
				(width 0.1524)
				(type default)
			)
			(layer "B.SilkS")
		)
		(fp_poly
			(pts
				(xy 0.508 0.2794) (xy 0.508 0.2286) (xy 0.635 0.2286) (xy 0.635 -0.254) (xy 0.5334 -0.254) (xy 0.5334 -0.2794)
				(xy -0.5334 -0.2794) (xy -0.5334 -0.254) (xy -0.635 -0.254) (xy -0.635 0.254) (xy -0.5334 0.254)
				(xy -0.5334 0.2794)
			)
			(stroke
				(width 0)
				(type default)
			)
			(fill no)
			(layer "B.CrtYd")
		)
		(pad "1" smd rect
			(at -0.40005 0)
			(size 0.4572 0.508)
			(layers "B.Cu" "B.Mask" "B.Paste")
			(net "P3V3_NODE1")
		)
		(pad "2" smd rect
			(at 0.40005 0)
			(size 0.4572 0.508)
			(layers "B.Cu" "B.Mask" "B.Paste")
			(net "N21699372")
		)
	)
)
